# BASEBOARD_FAB2 (Tioga Pass) — schematic netlist excerpt (pin names and nets, part order shuffled) for the footprints in the layout excerpt that follows; sources: Cadence DE-HDL packaged netlist, KiCad conversion of Wiwynn_Tioga_Pass_MB.brd

C7B6  CAP_A  0.1UF 16V 10% X7R  pkg 0402V  page 232 : A = VR_FET_SW_P12V_STBY_PVPP_DEF ; B = GND
RT5  RES  0 5.0% CHIP  pkg 0603  page 227 : A = VR_PVDDQ_KLM_PH1_BOOT ; B = VR_PVDDQ_KLM_PH1_BOOT_R

(kicad_pcb
	(version 20260206)
	(generator "pcbnew")
	(generator_version "10.0")
	(general
		(thickness 1.6)
		(legacy_teardrops no)
	)
	(paper "A4")
	(title_block
		(title "Wiwynn_Tioga_Pass_MB.brd")
		(comment 1 "Tioga Pass / footprints 1600-1601 of 4770")
	)
	(layers
		(0 "F.Cu" signal "TOP")
		(4 "In1.Cu" signal "L2GND")
		(6 "In2.Cu" signal "L3")
		(8 "In3.Cu" signal "L4GND")
		(10 "In4.Cu" signal "L5")
		(12 "In5.Cu" signal "L6GND")
		(14 "In6.Cu" signal "L7VCC")
		(16 "In7.Cu" signal "L8VCC")
		(18 "In8.Cu" signal "L9GND")
		(20 "In9.Cu" signal "L10")
		(22 "In10.Cu" signal "L11GND")
		(24 "In11.Cu" signal "L12")
		(26 "In12.Cu" signal "L13GND")
		(2 "B.Cu" signal "BOTTOM")
		(9 "F.Adhes" user "F.Adhesive")
		(11 "B.Adhes" user "B.Adhesive")
		(13 "F.Paste" user "Package Geometry/Pastemask Top")
		(15 "B.Paste" user "Package Geometry/Pastemask Bottom")
		(5 "F.SilkS" user "Ref Des/Silkscreen Top")
		(7 "B.SilkS" user "Ref Des/Silkscreen Bottom")
		(1 "F.Mask" user "Board Geometry/Soldermask Top")
		(3 "B.Mask" user "Board Geometry/Soldermask Bottom")
		(17 "Dwgs.User" user "User.Drawings")
		(19 "Cmts.User" user "User.Comments")
		(21 "Eco1.User" user "User.Eco1")
		(23 "Eco2.User" user "User.Eco2")
		(25 "Edge.Cuts" user "Board Geometry/Outline")
		(27 "Margin" user)
		(31 "F.CrtYd" user "Package Geometry/Place Bound Top")
		(29 "B.CrtYd" user "Package Geometry/Place Bound Bottom")
		(35 "F.Fab" user "Ref Des/Assembly Top")
		(33 "B.Fab" user "Ref Des/Assembly Bottom")
	)
	(footprint ""
		(layer "F.Cu")
		(at 348.361 -133.604 180)
		(property "Reference" "C7B6"
			(at 0 0 180)
			(layer "F.SilkS")
			(hide yes)
			(effects
				(font
					(size 1.27 1.27)
				)
			)
		)
		(property "Value" ""
			(at 0 0 180)
			(layer "F.Fab")
			(effects
				(font
					(size 1.27 1.27)
				)
			)
		)
		(duplicate_pad_numbers_are_jumpers no)
		(fp_poly
			(pts
				(xy 0.3048 -0.1016) (xy 0.3048 0.9906) (xy -0.3048 0.9906) (xy -0.3048 -0.1016)
			)
			(stroke
				(width 0)
				(type default)
			)
			(fill no)
			(layer "F.CrtYd")
		)
		(fp_line
			(start 0.3048 0.9906)
			(end 0.3048 -0.1016)
			(stroke
				(width 0.1)
				(type default)
			)
			(layer "F.Fab")
		)
		(fp_line
			(start 0.3048 -0.1016)
			(end -0.3048 -0.1016)
			(stroke
				(width 0.1)
				(type default)
			)
			(layer "F.Fab")
		)
		(fp_line
			(start -0.3048 0.9906)
			(end 0.3048 0.9906)
			(stroke
				(width 0.1)
				(type default)
			)
			(layer "F.Fab")
		)
		(fp_line
			(start -0.3048 -0.1016)
			(end -0.3048 0.9906)
			(stroke
				(width 0.1)
				(type default)
			)
			(layer "F.Fab")
		)
		(pad "1" smd rect
			(at 0 0 180)
			(size 0.508 0.508)
			(layers "F.Cu" "F.Mask" "F.Paste")
			(net "VR_FET_SW_P12V_STBY_PVPP_DEF")
		)
		(pad "2" smd rect
			(at 0 0.889 180)
			(size 0.508 0.508)
			(layers "F.Cu" "F.Mask" "F.Paste")
			(net "GND")
		)
		(zone
			(layer "F.Cu")
			(hatch none 0.5)
			(connect_pads
				(clearance 0)
			)
			(min_thickness 0.25)
			(keepout
				(tracks not_allowed)
				(vias allowed)
				(pads allowed)
				(copperpour not_allowed)
				(footprints allowed)
			)
			(placement
				(enabled no)
				(sheetname "")
			)
			(fill
				(thermal_gap 0.5)
				(thermal_bridge_width 0.5)
				(island_removal_mode 0)
			)
			(polygon
				(pts
					(xy 348.615 -134.239) (xy 348.107 -134.239) (xy 348.107 -133.858) (xy 348.615 -133.858)
				)
			)
		)
		(zone
			(layer "F.Cu")
			(hatch none 0.5)
			(connect_pads
				(clearance 0)
			)
			(min_thickness 0.25)
			(keepout
				(tracks allowed)
				(vias not_allowed)
				(pads allowed)
				(copperpour not_allowed)
				(footprints allowed)
			)
			(placement
				(enabled no)
				(sheetname "")
			)
			(fill
				(thermal_gap 0.5)
				(thermal_bridge_width 0.5)
				(island_removal_mode 0)
			)
			(polygon
				(pts
					(xy 348.615 -133.858) (xy 348.107 -133.858) (xy 348.107 -134.239) (xy 348.615 -134.239)
				)
			)
		)
	)
	(footprint ""
		(layer "F.Cu")
		(at -4.021074 -139.00531 90)
		(property "Reference" "RT5"
			(at 1.01473 0.656336 0)
			(unlocked yes)
			(layer "F.SilkS")
			(effects
				(font
					(size 0.4064 0.254)
					(thickness 0.1524)
				)
			)
		)
		(property "Value" ""
			(at 0 0 90)
			(layer "F.Fab")
			(effects
				(font
					(size 1.27 1.27)
				)
			)
		)
		(duplicate_pad_numbers_are_jumpers no)
		(fp_poly
			(pts
				(xy -0.4953 -0.2032) (xy 0.4953 -0.2032) (xy 0.4953 1.6002) (xy -0.4953 1.6002)
			)
			(stroke
				(width 0)
				(type default)
			)
			(fill no)
			(layer "F.CrtYd")
		)
		(fp_line
			(start 0.4953 -0.2032)
			(end 0.4953 1.6002)
			(stroke
				(width 0.1)
				(type default)
			)
			(layer "F.Fab")
		)
		(fp_line
			(start -0.4953 -0.2032)
			(end 0.4953 -0.2032)
			(stroke
				(width 0.1)
				(type default)
			)
			(layer "F.Fab")
		)
		(fp_line
			(start 0.4953 1.6002)
			(end -0.4953 1.6002)
			(stroke
				(width 0.1)
				(type default)
			)
			(layer "F.Fab")
		)
		(fp_line
			(start -0.4953 1.6002)
			(end -0.4953 -0.2032)
			(stroke
				(width 0.1)
				(type default)
			)
			(layer "F.Fab")
		)
		(pad "1" smd rect
			(at 0 0 90)
			(size 0.762 0.889)
			(layers "F.Cu" "F.Mask" "F.Paste")
			(net "VR_PVDDQ_KLM_PH1_BOOT")
		)
		(pad "2" smd rect
			(at 0 1.397 90)
			(size 0.762 0.889)
			(layers "F.Cu" "F.Mask" "F.Paste")
			(net "VR_PVDDQ_KLM_PH1_BOOT_R")
		)
		(zone
			(layer "F.Cu")
			(hatch none 0.5)
			(connect_pads
				(clearance 0)
			)
			(min_thickness 0.25)
			(keepout
				(tracks allowed)
				(vias not_allowed)
				(pads allowed)
				(copperpour not_allowed)
				(footprints allowed)
			)
			(placement
				(enabled no)
				(sheetname "")
			)
			(fill
				(thermal_gap 0.5)
				(thermal_bridge_width 0.5)
				(island_removal_mode 0)
			)
			(polygon
				(pts
					(xy -3.068574 -139.38631) (xy -3.576574 -139.38631) (xy -3.576574 -138.62431) (xy -3.068574 -138.62431)
				)
			)
		)
		(zone
			(layer "F.Cu")
			(hatch none 0.5)
			(connect_pads
				(clearance 0)
			)
			(min_thickness 0.25)
			(keepout
				(tracks not_allowed)
				(vias allowed)
				(pads allowed)
				(copperpour not_allowed)
				(footprints allowed)
			)
			(placement
				(enabled no)
				(sheetname "")
			)
			(fill
				(thermal_gap 0.5)
				(thermal_bridge_width 0.5)
				(island_removal_mode 0)
			)
			(polygon
				(pts
					(xy -3.068574 -138.62431) (xy -3.068574 -139.38631) (xy -3.576574 -139.38631) (xy -3.576574 -138.62431)
				)
			)
		)
	)
)
